# S9S_MB_2U (Grand Teton) — schematic netlist excerpt (pin names and nets, part order shuffled) for the footprints in the layout excerpt that follows; sources: Cadence DE-HDL packaged netlist, KiCad conversion of 03242023_DA0F0TMBIJ0_F0T_Motherboard_J_brd_V01_OCP.brd

J31  SCONN288_ADR50017P130CC  SCONN288_ADR50017-P130CC IO  pkg DDR288S_1-1VXB  page 112
  VIN_BULK0  = P12V_S3_AUX_CPU1_NVDIMM
  RFU0  = TP_CHH_CPU1_DIMM1_FRU_0
  VIN_MGMT  = P3V3_AUX
  HSCL  = I3C_SPD_DDREFGH_CPU1_LVC1_SCL_6
  HSDA  = I3C_SPD_DDREFGH_CPU1_LVC1_SDA
  VSS0  = GND
  DQ0_A  = M_H_CPU1_SA_DQ<0>
  VSS1  = GND
  DQ1_A  = M_H_CPU1_SA_DQ<1>
  VSS2  = GND
  DQS0_A_T  = M_H_CPU1_SA_DQS_DP<0>
  DQS0_A_C  = M_H_CPU1_SA_DQS_DN<0>
  VSS3  = GND
  DQ4_A  = M_H_CPU1_SA_DQ<4>
  VSS4  = GND
  DQ5_A  = M_H_CPU1_SA_DQ<5>
  VSS5  = GND
  DQ8_A  = M_H_CPU1_SA_DQ<8>
  VSS6  = GND
  DQ9_A  = M_H_CPU1_SA_DQ<9>
  VSS7  = GND
  DQS1_A_T  = M_H_CPU1_SA_DQS_DP<1>
  DQS1_A_C  = M_H_CPU1_SA_DQS_DN<1>
  VSS8  = GND
  DQ12_A  = M_H_CPU1_SA_DQ<12>
  VSS9  = GND
  DQ13_A  = M_H_CPU1_SA_DQ<13>
  VSS10  = GND
  DQ16_A  = M_H_CPU1_SA_DQ<16>
  VSS11  = GND
  DQ17_A  = M_H_CPU1_SA_DQ<17>
  VSS12  = GND
  DQS2_A_T  = M_H_CPU1_SA_DQS_DP<2>
  DQS2_A_C  = M_H_CPU1_SA_DQS_DN<2>
  VSS13  = GND
  DQ20_A  = M_H_CPU1_SA_DQ<20>
  VSS14  = GND
  DQ21_A  = M_H_CPU1_SA_DQ<21>
  VSS15  = GND
  DQ24_A  = M_H_CPU1_SA_DQ<24>
  VSS16  = GND
  DQ25_A  = M_H_CPU1_SA_DQ<25>
  VSS17  = GND
  DQS3_A_T  = M_H_CPU1_SA_DQS_DP<3>
  DQS3_A_C  = M_H_CPU1_SA_DQS_DN<3>
  VSS18  = GND
  DQ28_A  = M_H_CPU1_SA_DQ<28>
  VSS19  = GND
  DQ29_A  = M_H_CPU1_SA_DQ<29>
  VSS20  = GND
  CB0_A  = M_H_CPU1_SA_CB<0>
  VSS21  = GND
  CB1_A  = M_H_CPU1_SA_CB<1>
  VSS22  = GND
  DQS4_A_T  = M_H_CPU1_SA_DQS_DP<4>
  DQS4_A_C  = M_H_CPU1_SA_DQS_DN<4>
  VSS23  = GND
  CB4_A  = M_H_CPU1_SA_CB<4>
  VSS24  = GND
  CB5_A  = M_H_CPU1_SA_CB<5>
  VSS25  = GND
  ALERT_N  = M_H_CPU1_ALERT_N
  VSS26  = GND
  CS0_A_N  = M_H_CPU1_SA_CS_N<0>
  VSS27  = GND
  CA0_A  = M_H_CPU1_SA_CA<0>
  VSS28  = GND
  CA2_A  = M_H_CPU1_SA_CA<2>
  VSS29  = GND
  CA4_A  = M_H_CPU1_SA_CA<4>
  VSS30  = GND
  CA6_A  = M_H_CPU1_SA_CA<6>
  VSS31  = GND
  PAR_A  = M_H_CPU1_SA_PAR
  VSS32  = GND
  CA0_B  = M_H_CPU1_SB_CA<0>
  VSS33  = GND
  CA2_B  = M_H_CPU1_SB_CA<2>
  VSS34  = GND
  CA4_B  = M_H_CPU1_SB_CA<4>
  VSS35  = GND
  CA6_B  = M_H_CPU1_SB_CA<6>
  VSS36  = GND
  CS0_B_N  = M_H_CPU1_SB_CS_N<0>
  VSS37  = GND
  \lbd||rsp_a_n\  = M_H_CPU1_SA_RSP<0>
  \lbs||rsp_b_n\  = M_H_CPU1_SB_RSP<0>
  VSS38  = GND
  CB4_B  = M_H_CPU1_SB_CB<4>
  VSS39  = GND
  CB5_B  = M_H_CPU1_SB_CB<5>
  VSS40  = GND
  \dqs9_b_t||tdqs9_b_t||dbi4_b_n\  = M_H_CPU1_SB_DQS_DP<9>
  \dqs9_b_c||tdqs9_b_c\  = M_H_CPU1_SB_DQS_DN<9>
  VSS41  = GND
  CB0_B  = M_H_CPU1_SB_CB<0>
  VSS42  = GND
  CB1_B  = M_H_CPU1_SB_CB<1>
  VSS43  = GND
  DQ0_B  = M_H_CPU1_SB_DQ<0>
  VSS44  = GND
  DQ1_B  = M_H_CPU1_SB_DQ<1>
  VSS45  = GND
  DQS0_B_T  = M_H_CPU1_SB_DQS_DP<0>
  DQS0_B_C  = M_H_CPU1_SB_DQS_DN<0>
  VSS46  = GND
  DQ4_B  = M_H_CPU1_SB_DQ<4>
  VSS47  = GND
  DQ5_B  = M_H_CPU1_SB_DQ<5>
  VSS48  = GND
  DQ8_B  = M_H_CPU1_SB_DQ<8>
  VSS49  = GND
  DQ9_B  = M_H_CPU1_SB_DQ<9>
  VSS50  = GND
  DQS1_B_T  = M_H_CPU1_SB_DQS_DP<1>
  DQS1_B_C  = M_H_CPU1_SB_DQS_DN<1>
  VSS51  = GND
  DQ12_B  = M_H_CPU1_SB_DQ<12>
  VSS52  = GND
  DQ13_B  = M_H_CPU1_SB_DQ<13>
  VSS53  = GND
  DQ16_B  = M_H_CPU1_SB_DQ<16>
  VSS54  = GND
  DQ17_B  = M_H_CPU1_SB_DQ<17>
  VSS55  = GND
  DQS2_B_T  = M_H_CPU1_SB_DQS_DP<2>
  DQS2_B_C  = M_H_CPU1_SB_DQS_DN<2>
  VSS56  = GND
  DQ20_B  = M_H_CPU1_SB_DQ<20>
  VSS57  = GND
  DQ21_B  = M_H_CPU1_SB_DQ<21>
  VSS58  = GND
  DQ24_B  = M_H_CPU1_SB_DQ<24>
  VSS59  = GND
  DQ25_B  = M_H_CPU1_SB_DQ<25>
  VSS60  = GND
  DQS3_B_T  = M_H_CPU1_SB_DQS_DP<3>
  DQS3_B_C  = M_H_CPU1_SB_DQS_DN<3>
  VSS61  = GND
  DQ28_B  = M_H_CPU1_SB_DQ<28>
  VSS62  = GND
  DQ29_B  = M_H_CPU1_SB_DQ<29>
  VSS63  = GND
  RFU1  = TP_CHH_CPU1_DIMM1_FRU_1
  VIN_BULK1  = P12V_S3_AUX_CPU1_NVDIMM
  VIN_BULK2  = P12V_S3_AUX_CPU1_NVDIMM
  \pwr_good||fail_n\  = PWRGD_CHH_CPU1_DIMM1
  HSA  = PD_CHH_CPU1_DIMM1_SAA
  RFU2  = TP_CHH_CPU1_DIMM1_FRU_2
  RFU3  = TP_CHH_CPU1_DIMM1_FRU_3
  VSS64  = GND
  DQ2_A  = M_H_CPU1_SA_DQ<2>
  VSS65  = GND
  DQ3_A  = M_H_CPU1_SA_DQ<3>
  VSS66  = GND
  \dqs5_a_c||tdqs5_a_c||dqs5_a_t||tdqs5_a_t\  = M_H_CPU1_SA_DQS_DN<5>
  \dqs5_a_t||tdqs5_a_t\  = M_H_CPU1_SA_DQS_DP<5>
  VSS67  = GND
  DQ6_A  = M_H_CPU1_SA_DQ<6>
  VSS68  = GND
  DQ7_A  = M_H_CPU1_SA_DQ<7>
  VSS69  = GND
  DQ10_A  = M_H_CPU1_SA_DQ<10>
  VSS70  = GND
  DQ11_A  = M_H_CPU1_SA_DQ<11>
  VSS71  = GND
  \dqs6_a_c||tdqs6_a_c||dqs6_a_t||tdqs6_a_t\  = M_H_CPU1_SA_DQS_DN<6>
  \dqs6_a_t||tdqs6_a_t\  = M_H_CPU1_SA_DQS_DP<6>
  VSS72  = GND
  DQ14_A  = M_H_CPU1_SA_DQ<14>
  VSS73  = GND
  DQ15_A  = M_H_CPU1_SA_DQ<15>
  VSS74  = GND
  DQ18_A  = M_H_CPU1_SA_DQ<18>
  VSS75  = GND
  DQ19_A  = M_H_CPU1_SA_DQ<19>
  VSS76  = GND
  \dqs7_a_c||tdqs7_a_c\  = M_H_CPU1_SA_DQS_DN<7>
  \dqs7_a_t||tdqs7_a_t\  = M_H_CPU1_SA_DQS_DP<7>
  VSS77  = GND
  DQ22_A  = M_H_CPU1_SA_DQ<22>
  VSS78  = GND
  DQ23_A  = M_H_CPU1_SA_DQ<23>
  VSS79  = GND
  DQ26_A  = M_H_CPU1_SA_DQ<26>
  VSS80  = GND
  DQ27_A  = M_H_CPU1_SA_DQ<27>
  VSS81  = GND
  \dqs8_a_c||tdqs8_a_c\  = M_H_CPU1_SA_DQS_DN<8>
  \dqs8_a_t||tdqs8_a_t\  = M_H_CPU1_SA_DQS_DP<8>
  VSS82  = GND
  DQ30_A  = M_H_CPU1_SA_DQ<30>
  VSS83  = GND
  DQ31_A  = M_H_CPU1_SA_DQ<31>
  VSS84  = GND
  CB2_A  = M_H_CPU1_SA_CB<2>
  VSS85  = GND
  CB3_A  = M_H_CPU1_SA_CB<3>
  VSS86  = GND
  \dqs9_a_c||tdqs9_a_c\  = M_H_CPU1_SA_DQS_DN<9>
  \dqs9_a_t||tdqs9_a_t\  = M_H_CPU1_SA_DQS_DP<9>
  VSS87  = GND
  CB6_A  = M_H_CPU1_SA_CB<6>
  VSS88  = GND
  CB7_A  = M_H_CPU1_SA_CB<7>
  VSS89  = GND
  RESET_N  = RST_M_GH_CPU1_FPGA_N
  VSS90  = GND
  CS1_A_N  = M_H_CPU1_SA_CS_N<1>
  VSS91  = GND
  CA1_A  = M_H_CPU1_SA_CA<1>
  VSS92  = GND
  CA3_A  = M_H_CPU1_SA_CA<3>
  VSS93  = GND
  CA5_A  = M_H_CPU1_SA_CA<5>
  VSS94  = GND
  CK_T  = M_H_CPU1_CLK_DP<0>
  CK_C  = M_H_CPU1_CLK_DN<0>
  VSS95  = GND
  RFU4  = TP_CHH_CPU1_DIMM1_FRU_4
  CA1_B  = M_H_CPU1_SB_CA<1>
  VSS96  = GND
  CA3_B  = M_H_CPU1_SB_CA<3>
  VSS97  = GND
  CA5_B  = M_H_CPU1_SB_CA<5>
  VSS98  = GND
  PAR_B  = M_H_CPU1_SB_PAR
  VSS99  = GND
  CS1_B_N  = M_H_CPU1_SB_CS_N<1>
  VSS100  = GND
  RFU5  = TP_CHH_CPU1_DIMM1_FRU_5
  RFU6  = TP_CHH_CPU1_DIMM1_FRU_6
  VSS101  = GND
  CB6_B  = M_H_CPU1_SB_CB<6>
  VSS102  = GND
  CB7_B  = M_H_CPU1_SB_CB<7>
  VSS103  = GND
  DQS4_B_C  = M_H_CPU1_SB_DQS_DN<4>
  DQS4_B_T  = M_H_CPU1_SB_DQS_DP<4>
  VSS104  = GND
  CB2_B  = M_H_CPU1_SB_CB<2>
  VSS105  = GND
  CB3_B  = M_H_CPU1_SB_CB<3>
  VSS106  = GND
  DQ2_B  = M_H_CPU1_SB_DQ<2>
  VSS107  = GND
  DQ3_B  = M_H_CPU1_SB_DQ<3>
  VSS108  = GND
  \dqs5_b_c||tdqs5_b_c\  = M_H_CPU1_SB_DQS_DN<5>
  \dqs5_b_t||tdqs5_b_t\  = M_H_CPU1_SB_DQS_DP<5>
  VSS109  = GND
  DQ6_B  = M_H_CPU1_SB_DQ<6>
  VSS110  = GND
  DQ7_B  = M_H_CPU1_SB_DQ<7>
  VSS111  = GND
  DQ10_B  = M_H_CPU1_SB_DQ<10>
  VSS112  = GND
  DQ11_B  = M_H_CPU1_SB_DQ<11>
  VSS113  = GND
  \dqs6_b_c||tdqs6_b_c\  = M_H_CPU1_SB_DQS_DN<6>
  \dqs6_b_t||tdqs6_b_t\  = M_H_CPU1_SB_DQS_DP<6>
  VSS114  = GND
  DQ14_B  = M_H_CPU1_SB_DQ<14>
  VSS115  = GND
  DQ15_B  = M_H_CPU1_SB_DQ<15>
  VSS116  = GND
  DQ18_B  = M_H_CPU1_SB_DQ<18>
  VSS117  = GND
  DQ19_B  = M_H_CPU1_SB_DQ<19>
  VSS118  = GND
  \dqs7_b_c||tdqs7_b_c\  = M_H_CPU1_SB_DQS_DN<7>
  \dqs7_b_t||tdqs7_b_t\  = M_H_CPU1_SB_DQS_DP<7>
  VSS119  = GND
  DQ22_B  = M_H_CPU1_SB_DQ<22>
  VSS120  = GND
  DQ23_B  = M_H_CPU1_SB_DQ<23>
  VSS121  = GND
  DQ26_B  = M_H_CPU1_SB_DQ<26>
  VSS122  = GND
  DQ27_B  = M_H_CPU1_SB_DQ<27>
  VSS123  = GND
  \dqs8_b_c||tdqs8_b_c\  = M_H_CPU1_SB_DQS_DN<8>
  \dqs8_b_t||tdqs8_b_t\  = M_H_CPU1_SB_DQS_DP<8>
  VSS124  = GND
  DQ30_B  = M_H_CPU1_SB_DQ<30>
  VSS125  = GND
  DQ31_B  = M_H_CPU1_SB_DQ<31>
  VSS126  = GND
  G1  = GND
  G2  = GND
  G3  = GND

(kicad_pcb
	(version 20260206)
	(generator "pcbnew")
	(generator_version "10.0")
	(general
		(thickness 1.6)
		(legacy_teardrops no)
	)
	(paper "A4")
	(title_block
		(title "03242023_DA0F0TMBIJ0_F0T_Motherboard_J_brd_V01_OCP.brd")
		(comment 1 "Grand Teton / footprint 3900 of 6105 (J31), pads 229-274 of 291")
	)
	(layers
		(0 "F.Cu" signal "TOP")
		(4 "In1.Cu" signal "GND")
		(6 "In2.Cu" signal "IN1")
		(8 "In3.Cu" signal "GND1")
		(10 "In4.Cu" signal "IN2")
		(12 "In5.Cu" signal "GND2")
		(14 "In6.Cu" signal "IN3")
		(16 "In7.Cu" signal "GND3")
		(18 "In8.Cu" signal "VCC")
		(20 "In9.Cu" signal "VCC1")
		(22 "In10.Cu" signal "GND4")
		(24 "In11.Cu" signal "IN4")
		(26 "In12.Cu" signal "GND5")
		(28 "In13.Cu" signal "IN5")
		(30 "In14.Cu" signal "GND6")
		(32 "In15.Cu" signal "IN6")
		(34 "In16.Cu" signal "GND7")
		(2 "B.Cu" signal "BOTTOM")
		(9 "F.Adhes" user "F.Adhesive")
		(11 "B.Adhes" user "B.Adhesive")
		(13 "F.Paste" user "Package Geometry/Pastemask Top")
		(15 "B.Paste" user "Package Geometry/Pastemask Bottom")
		(5 "F.SilkS" user "Ref Des/Silkscreen Top")
		(7 "B.SilkS" user "Ref Des/Silkscreen Bottom")
		(1 "F.Mask" user "Board Geometry/Soldermask Top")
		(3 "B.Mask" user "Board Geometry/Soldermask Bottom")
		(17 "Dwgs.User" user "User.Drawings")
		(19 "Cmts.User" user "User.Comments")
		(21 "Eco1.User" user "User.Eco1")
		(23 "Eco2.User" user "User.Eco2")
		(25 "Edge.Cuts" user "Board Geometry/Outline")
		(27 "Margin" user)
		(31 "F.CrtYd" user "Package Geometry/Place Bound Top")
		(29 "B.CrtYd" user "Package Geometry/Place Bound Bottom")
		(35 "F.Fab" user "Ref Des/Assembly Top")
		(33 "B.Fab" user "Ref Des/Assembly Bottom")
	)
	(footprint ""
		(layer "F.Cu")
		(at 213.66988 -258.091686)
		(property "Reference" "J31"
			(at -3.683 -81.702148 0)
			(unlocked yes)
			(layer "F.SilkS")
			(effects
				(font
					(size 0.7874 0.5842)
					(thickness 0.1524)
				)
				(justify left)
			)
		)
		(property "Value" ""
			(at 0 0 0)
			(layer "F.Fab")
			(effects
				(font
					(size 1.27 1.27)
				)
			)
		)
		(duplicate_pad_numbers_are_jumpers no)
		(pad "229" smd rect
			(at 2.050034 13.17498 270)
			(size 0.519938 1.4986)
			(layers "F.Cu" "F.Mask" "F.Paste")
			(net "M_H_CPU1_SB_CS_N<1>")
		)
		(pad "230" smd rect
			(at 2.050034 14.025118 270)
			(size 0.519938 1.4986)
			(layers "F.Cu" "F.Mask" "F.Paste")
			(net "GND")
		)
		(pad "231" smd rect
			(at 2.050034 14.875002 270)
			(size 0.519938 1.4986)
			(layers "F.Cu" "F.Mask" "F.Paste")
			(net "TP_CHH_CPU1_DIMM1_FRU_5")
		)
		(pad "232" smd rect
			(at 2.050034 15.724886 270)
			(size 0.519938 1.4986)
			(layers "F.Cu" "F.Mask" "F.Paste")
			(net "TP_CHH_CPU1_DIMM1_FRU_6")
		)
		(pad "233" smd rect
			(at 2.050034 16.575024 270)
			(size 0.519938 1.4986)
			(layers "F.Cu" "F.Mask" "F.Paste")
			(net "GND")
		)
		(pad "234" smd rect
			(at 2.050034 17.424908 270)
			(size 0.519938 1.4986)
			(layers "F.Cu" "F.Mask" "F.Paste")
			(net "M_H_CPU1_SB_CB<6>")
		)
		(pad "235" smd rect
			(at 2.050034 18.275046 270)
			(size 0.519938 1.4986)
			(layers "F.Cu" "F.Mask" "F.Paste")
			(net "GND")
		)
		(pad "236" smd rect
			(at 2.050034 19.12493 270)
			(size 0.519938 1.4986)
			(layers "F.Cu" "F.Mask" "F.Paste")
			(net "M_H_CPU1_SB_CB<7>")
		)
		(pad "237" smd rect
			(at 2.050034 19.975068 270)
			(size 0.519938 1.4986)
			(layers "F.Cu" "F.Mask" "F.Paste")
			(net "GND")
		)
		(pad "238" smd rect
			(at 2.050034 20.824952 270)
			(size 0.519938 1.4986)
			(layers "F.Cu" "F.Mask" "F.Paste")
			(net "M_H_CPU1_SB_DQS_DN<4>")
		)
		(pad "239" smd rect
			(at 2.050034 21.67509 270)
			(size 0.519938 1.4986)
			(layers "F.Cu" "F.Mask" "F.Paste")
			(net "M_H_CPU1_SB_DQS_DP<4>")
		)
		(pad "240" smd rect
			(at 2.050034 22.524974 270)
			(size 0.519938 1.4986)
			(layers "F.Cu" "F.Mask" "F.Paste")
			(net "GND")
		)
		(pad "241" smd rect
			(at 2.050034 23.375112 270)
			(size 0.519938 1.4986)
			(layers "F.Cu" "F.Mask" "F.Paste")
			(net "M_H_CPU1_SB_CB<2>")
		)
		(pad "242" smd rect
			(at 2.050034 24.224996 270)
			(size 0.519938 1.4986)
			(layers "F.Cu" "F.Mask" "F.Paste")
			(net "GND")
		)
		(pad "243" smd rect
			(at 2.050034 25.07488 270)
			(size 0.519938 1.4986)
			(layers "F.Cu" "F.Mask" "F.Paste")
			(net "M_H_CPU1_SB_CB<3>")
		)
		(pad "244" smd rect
			(at 2.050034 25.925018 270)
			(size 0.519938 1.4986)
			(layers "F.Cu" "F.Mask" "F.Paste")
			(net "GND")
		)
		(pad "245" smd rect
			(at 2.050034 26.774902 270)
			(size 0.519938 1.4986)
			(layers "F.Cu" "F.Mask" "F.Paste")
			(net "M_H_CPU1_SB_DQ<2>")
		)
		(pad "246" smd rect
			(at 2.050034 27.62504 270)
			(size 0.519938 1.4986)
			(layers "F.Cu" "F.Mask" "F.Paste")
			(net "GND")
		)
		(pad "247" smd rect
			(at 2.050034 28.474924 270)
			(size 0.519938 1.4986)
			(layers "F.Cu" "F.Mask" "F.Paste")
			(net "M_H_CPU1_SB_DQ<3>")
		)
		(pad "248" smd rect
			(at 2.050034 29.325062 270)
			(size 0.519938 1.4986)
			(layers "F.Cu" "F.Mask" "F.Paste")
			(net "GND")
		)
		(pad "249" smd rect
			(at 2.050034 30.174946 270)
			(size 0.519938 1.4986)
			(layers "F.Cu" "F.Mask" "F.Paste")
			(net "M_H_CPU1_SB_DQS_DN<5>")
		)
		(pad "250" smd rect
			(at 2.050034 31.025084 270)
			(size 0.519938 1.4986)
			(layers "F.Cu" "F.Mask" "F.Paste")
			(net "M_H_CPU1_SB_DQS_DP<5>")
		)
		(pad "251" smd rect
			(at 2.050034 31.874968 270)
			(size 0.519938 1.4986)
			(layers "F.Cu" "F.Mask" "F.Paste")
			(net "GND")
		)
		(pad "252" smd rect
			(at 2.050034 32.725106 270)
			(size 0.519938 1.4986)
			(layers "F.Cu" "F.Mask" "F.Paste")
			(net "M_H_CPU1_SB_DQ<6>")
		)
		(pad "253" smd rect
			(at 2.050034 33.57499 270)
			(size 0.519938 1.4986)
			(layers "F.Cu" "F.Mask" "F.Paste")
			(net "GND")
		)
		(pad "254" smd rect
			(at 2.050034 34.425128 270)
			(size 0.519938 1.4986)
			(layers "F.Cu" "F.Mask" "F.Paste")
			(net "M_H_CPU1_SB_DQ<7>")
		)
		(pad "255" smd rect
			(at 2.050034 35.275012 270)
			(size 0.519938 1.4986)
			(layers "F.Cu" "F.Mask" "F.Paste")
			(net "GND")
		)
		(pad "256" smd rect
			(at 2.050034 36.124896 270)
			(size 0.519938 1.4986)
			(layers "F.Cu" "F.Mask" "F.Paste")
			(net "M_H_CPU1_SB_DQ<10>")
		)
		(pad "257" smd rect
			(at 2.050034 36.975034 270)
			(size 0.519938 1.4986)
			(layers "F.Cu" "F.Mask" "F.Paste")
			(net "GND")
		)
		(pad "258" smd rect
			(at 2.050034 37.824918 270)
			(size 0.519938 1.4986)
			(layers "F.Cu" "F.Mask" "F.Paste")
			(net "M_H_CPU1_SB_DQ<11>")
		)
		(pad "259" smd rect
			(at 2.050034 38.675056 270)
			(size 0.519938 1.4986)
			(layers "F.Cu" "F.Mask" "F.Paste")
			(net "GND")
		)
		(pad "260" smd rect
			(at 2.050034 39.52494 270)
			(size 0.519938 1.4986)
			(layers "F.Cu" "F.Mask" "F.Paste")
			(net "M_H_CPU1_SB_DQS_DN<6>")
		)
		(pad "261" smd rect
			(at 2.050034 40.375078 270)
			(size 0.519938 1.4986)
			(layers "F.Cu" "F.Mask" "F.Paste")
			(net "M_H_CPU1_SB_DQS_DP<6>")
		)
		(pad "262" smd rect
			(at 2.050034 41.224962 270)
			(size 0.519938 1.4986)
			(layers "F.Cu" "F.Mask" "F.Paste")
			(net "GND")
		)
		(pad "263" smd rect
			(at 2.050034 42.0751 270)
			(size 0.519938 1.4986)
			(layers "F.Cu" "F.Mask" "F.Paste")
			(net "M_H_CPU1_SB_DQ<14>")
		)
		(pad "264" smd rect
			(at 2.050034 42.924984 270)
			(size 0.519938 1.4986)
			(layers "F.Cu" "F.Mask" "F.Paste")
			(net "GND")
		)
		(pad "265" smd rect
			(at 2.050034 43.775122 270)
			(size 0.519938 1.4986)
			(layers "F.Cu" "F.Mask" "F.Paste")
			(net "M_H_CPU1_SB_DQ<15>")
		)
		(pad "266" smd rect
			(at 2.050034 44.625006 270)
			(size 0.519938 1.4986)
			(layers "F.Cu" "F.Mask" "F.Paste")
			(net "GND")
		)
		(pad "267" smd rect
			(at 2.050034 45.47489 270)
			(size 0.519938 1.4986)
			(layers "F.Cu" "F.Mask" "F.Paste")
			(net "M_H_CPU1_SB_DQ<18>")
		)
		(pad "268" smd rect
			(at 2.050034 46.325028 270)
			(size 0.519938 1.4986)
			(layers "F.Cu" "F.Mask" "F.Paste")
			(net "GND")
		)
		(pad "269" smd rect
			(at 2.050034 47.174912 270)
			(size 0.519938 1.4986)
			(layers "F.Cu" "F.Mask" "F.Paste")
			(net "M_H_CPU1_SB_DQ<19>")
		)
		(pad "270" smd rect
			(at 2.050034 48.02505 270)
			(size 0.519938 1.4986)
			(layers "F.Cu" "F.Mask" "F.Paste")
			(net "GND")
		)
		(pad "271" smd rect
			(at 2.050034 48.874934 270)
			(size 0.519938 1.4986)
			(layers "F.Cu" "F.Mask" "F.Paste")
			(net "M_H_CPU1_SB_DQS_DN<7>")
		)
		(pad "272" smd rect
			(at 2.050034 49.725072 270)
			(size 0.519938 1.4986)
			(layers "F.Cu" "F.Mask" "F.Paste")
			(net "M_H_CPU1_SB_DQS_DP<7>")
		)
		(pad "273" smd rect
			(at 2.050034 50.574956 270)
			(size 0.519938 1.4986)
			(layers "F.Cu" "F.Mask" "F.Paste")
			(net "GND")
		)
		(pad "274" smd rect
			(at 2.050034 51.425094 270)
			(size 0.519938 1.4986)
			(layers "F.Cu" "F.Mask" "F.Paste")
			(net "M_H_CPU1_SB_DQ<22>")
		)
	)
)
